(kicad_pcb
	(version 20260206)
	(generator "pcbnew")
	(generator_version "10.0")
	(general
		(thickness 1.6)
		(legacy_teardrops no)
	)
	(paper "A4")
	(title_block
		(title "Wiwynn_Tioga_Pass_MB.brd")
		(comment 1 "Tioga Pass / footprint 190 of 4770 (U2D1), pads 2295-2405 of 3647")
	)
	(layers
		(0 "F.Cu" signal "TOP")
		(4 "In1.Cu" signal "L2GND")
		(6 "In2.Cu" signal "L3")
		(8 "In3.Cu" signal "L4GND")
		(10 "In4.Cu" signal "L5")
		(12 "In5.Cu" signal "L6GND")
		(14 "In6.Cu" signal "L7VCC")
		(16 "In7.Cu" signal "L8VCC")
		(18 "In8.Cu" signal "L9GND")
		(20 "In9.Cu" signal "L10")
		(22 "In10.Cu" signal "L11GND")
		(24 "In11.Cu" signal "L12")
		(26 "In12.Cu" signal "L13GND")
		(2 "B.Cu" signal "BOTTOM")
		(9 "F.Adhes" user "F.Adhesive")
		(11 "B.Adhes" user "B.Adhesive")
		(13 "F.Paste" user "Package Geometry/Pastemask Top")
		(15 "B.Paste" user "Package Geometry/Pastemask Bottom")
		(5 "F.SilkS" user "Ref Des/Silkscreen Top")
		(7 "B.SilkS" user "Ref Des/Silkscreen Bottom")
		(1 "F.Mask" user "Board Geometry/Soldermask Top")
		(3 "B.Mask" user "Board Geometry/Soldermask Bottom")
		(17 "Dwgs.User" user "User.Drawings")
		(19 "Cmts.User" user "User.Comments")
		(21 "Eco1.User" user "User.Eco1")
		(23 "Eco2.User" user "User.Eco2")
		(25 "Edge.Cuts" user "Board Geometry/Outline")
		(27 "Margin" user)
		(31 "F.CrtYd" user "Package Geometry/Place Bound Top")
		(29 "B.CrtYd" user "Package Geometry/Place Bound Bottom")
		(35 "F.Fab" user "Ref Des/Assembly Top")
		(33 "B.Fab" user "Ref Des/Assembly Bottom")
	)
	(footprint ""
		(layer "F.Cu")
		(at 104.99979 -76.550012 180)
		(property "Reference" "U2D1"
			(at 25.19299 30.484318 0)
			(unlocked yes)
			(layer "F.SilkS")
			(effects
				(font
					(size 0.7874 0.5842)
					(thickness 0.1524)
				)
			)
		)
		(property "Value" ""
			(at 0 0 180)
			(layer "F.Fab")
			(effects
				(font
					(size 1.27 1.27)
				)
			)
		)
		(duplicate_pad_numbers_are_jumpers no)
		(pad "DJ40" smd circle
			(at -3.769106 18.483072)
			(size 0.4318 0.4318)
			(layers "F.Cu" "F.Mask" "F.Paste")
			(net "M_M_DQS_DP<4>")
		)
		(pad "DJ42" smd circle
			(at -2.052066 18.483072)
			(size 0.4318 0.4318)
			(layers "F.Cu" "F.Mask" "F.Paste")
			(net "GND")
		)
		(pad "DJ44" smd circle
			(at 1.193546 16.683228)
			(size 0.508 0.508)
			(layers "F.Cu" "F.Mask" "F.Paste")
			(net "SVID_DIO1_CPU1")
		)
		(pad "DJ46" smd circle
			(at 2.910586 16.683228)
			(size 0.4318 0.4318)
			(layers "F.Cu" "F.Mask" "F.Paste")
			(net "M_M_CS_N<2>")
		)
		(pad "DJ48" smd circle
			(at 4.627626 16.683228)
			(size 0.4318 0.4318)
			(layers "F.Cu" "F.Mask" "F.Paste")
			(net "M_M_CS_N<5>")
		)
		(pad "DJ50" smd circle
			(at 6.344412 16.683228)
			(size 0.4318 0.4318)
			(layers "F.Cu" "F.Mask" "F.Paste")
			(net "M_M_MA<14>")
		)
		(pad "DJ52" smd circle
			(at 8.061452 16.683228)
			(size 0.4318 0.4318)
			(layers "F.Cu" "F.Mask" "F.Paste")
			(net "M_M_BA<0>")
		)
		(pad "DJ54" smd circle
			(at 9.778492 16.683228)
			(size 0.4318 0.4318)
			(layers "F.Cu" "F.Mask" "F.Paste")
			(net "M_M_CLK_DP<0>")
		)
		(pad "DJ56" smd circle
			(at 11.495532 16.683228)
			(size 0.4318 0.4318)
			(layers "F.Cu" "F.Mask" "F.Paste")
			(net "M_M_CLK_DP<2>")
		)
		(pad "DJ58" smd circle
			(at 13.212572 16.683228)
			(size 0.4318 0.4318)
			(layers "F.Cu" "F.Mask" "F.Paste")
			(net "M_M_MA<4>")
		)
		(pad "DJ60" smd circle
			(at 14.929612 16.683228)
			(size 0.4318 0.4318)
			(layers "F.Cu" "F.Mask" "F.Paste")
			(net "M_L_MA<8>")
		)
		(pad "DJ62" smd circle
			(at 16.646398 16.683228)
			(size 0.4318 0.4318)
			(layers "F.Cu" "F.Mask" "F.Paste")
			(net "M_L_BG<0>")
		)
		(pad "DJ64" smd circle
			(at 18.363438 16.683228)
			(size 0.4318 0.4318)
			(layers "F.Cu" "F.Mask" "F.Paste")
			(net "PVDDQ_KLM")
		)
		(pad "DJ66" smd circle
			(at 20.080478 16.683228)
			(size 0.4318 0.4318)
			(layers "F.Cu" "F.Mask" "F.Paste")
			(net "TP_CPU1_RSVD_40")
		)
		(pad "DJ68" smd circle
			(at 21.797518 16.683228)
			(size 0.4318 0.4318)
			(layers "F.Cu" "F.Mask" "F.Paste")
			(net "GND")
		)
		(pad "DJ70" smd circle
			(at 23.514558 16.683228)
			(size 0.4318 0.4318)
			(layers "F.Cu" "F.Mask" "F.Paste")
			(net "M_M_DQS_DN<11>")
		)
		(pad "DJ72" smd circle
			(at 25.231598 16.683228)
			(size 0.4318 0.4318)
			(layers "F.Cu" "F.Mask" "F.Paste")
			(net "M_M_DQ<17>")
		)
		(pad "DJ74" smd circle
			(at 26.948384 16.683228)
			(size 0.4318 0.4318)
			(layers "F.Cu" "F.Mask" "F.Paste")
			(net "GND")
		)
		(pad "DJ76" smd circle
			(at 28.665424 16.683228)
			(size 0.4318 0.4318)
			(layers "F.Cu" "F.Mask" "F.Paste")
			(net "M_M_DQ<11>")
		)
		(pad "DJ78" smd circle
			(at 30.382464 16.683228)
			(size 0.4318 0.4318)
			(layers "F.Cu" "F.Mask" "F.Paste")
			(net "GND")
		)
		(pad "DJ80" smd circle
			(at 32.099504 16.683228)
			(size 0.4318 0.4318)
			(layers "F.Cu" "F.Mask" "F.Paste")
			(net "M_K_DQ<21>")
		)
		(pad "DJ82" smd circle
			(at 33.816544 16.683228)
			(size 0.4318 0.4318)
			(layers "F.Cu" "F.Mask" "F.Paste")
			(net "GND")
		)
		(pad "DJ84" smd circle
			(at 35.533584 16.683228)
			(size 0.4318 0.4318)
			(layers "F.Cu" "F.Mask" "F.Paste")
			(net "GND")
		)
		(pad "DK3" smd circle
			(at -35.533584 18.978372)
			(size 0.4318 0.4318)
			(layers "F.Cu" "F.Mask" "F.Paste")
			(net "TP_P3E_CPU1_PE1_MP_TXN<5>")
		)
		(pad "DK5" smd circle
			(at -33.816544 18.978372)
			(size 0.4318 0.4318)
			(layers "F.Cu" "F.Mask" "F.Paste")
			(net "P3E_CPU1_PE3_MP_TXP<10>")
		)
		(pad "DK7" smd circle
			(at -32.099504 18.978372)
			(size 0.4318 0.4318)
			(layers "F.Cu" "F.Mask" "F.Paste")
			(net "GND")
		)
		(pad "DK9" smd circle
			(at -30.382464 18.978372)
			(size 0.4318 0.4318)
			(layers "F.Cu" "F.Mask" "F.Paste")
			(net "TP_P3E_CPU1_PE1_MP_RXN<6>")
		)
		(pad "DK11" smd circle
			(at -28.665424 18.978372)
			(size 0.4318 0.4318)
			(layers "F.Cu" "F.Mask" "F.Paste")
			(net "TP_P3E_CPU1_PE1_RSR3_RXP<8>")
		)
		(pad "DK13" smd circle
			(at -26.948384 18.978372)
			(size 0.4318 0.4318)
			(layers "F.Cu" "F.Mask" "F.Paste")
			(net "P3E_CPU1_PE3_MP_RXP<8>")
		)
		(pad "DK15" smd circle
			(at -25.231598 18.978372)
			(size 0.4318 0.4318)
			(layers "F.Cu" "F.Mask" "F.Paste")
			(net "TP_CPU1_RSVD_39")
		)
		(pad "DK17" smd circle
			(at -23.514558 18.978372)
			(size 0.4318 0.4318)
			(layers "F.Cu" "F.Mask" "F.Paste")
			(net "TP_CPU1_UPI2_RSVD_CJ14")
		)
		(pad "DK19" smd circle
			(at -21.797518 18.978372)
			(size 0.4318 0.4318)
			(layers "F.Cu" "F.Mask" "F.Paste")
			(net "TP_CPU1_UPI2_RSVD_CD11")
		)
		(pad "DK21" smd circle
			(at -20.080478 18.978372)
			(size 0.4318 0.4318)
			(layers "F.Cu" "F.Mask" "F.Paste")
			(net "PVCCIO_CPU1")
		)
		(pad "DK23" smd circle
			(at -18.363438 18.978372)
			(size 0.4318 0.4318)
			(layers "F.Cu" "F.Mask" "F.Paste")
			(net "GND")
		)
		(pad "DK25" smd circle
			(at -16.646398 18.978372)
			(size 0.4318 0.4318)
			(layers "F.Cu" "F.Mask" "F.Paste")
			(net "M_L_DQ<63>")
		)
		(pad "DK27" smd circle
			(at -14.929612 18.978372)
			(size 0.4318 0.4318)
			(layers "F.Cu" "F.Mask" "F.Paste")
			(net "M_L_DQ<57>")
		)
		(pad "DK29" smd circle
			(at -13.212572 18.978372)
			(size 0.4318 0.4318)
			(layers "F.Cu" "F.Mask" "F.Paste")
			(net "GND")
		)
		(pad "DK31" smd circle
			(at -11.495532 18.978372)
			(size 0.4318 0.4318)
			(layers "F.Cu" "F.Mask" "F.Paste")
			(net "M_M_DQ<47>")
		)
		(pad "DK33" smd circle
			(at -9.778492 18.978372)
			(size 0.4318 0.4318)
			(layers "F.Cu" "F.Mask" "F.Paste")
			(net "M_M_DQ<41>")
		)
		(pad "DK35" smd circle
			(at -8.061452 18.978372)
			(size 0.4318 0.4318)
			(layers "F.Cu" "F.Mask" "F.Paste")
			(net "GND")
		)
		(pad "DK37" smd circle
			(at -6.344412 18.978372)
			(size 0.4318 0.4318)
			(layers "F.Cu" "F.Mask" "F.Paste")
			(net "TP_CPU1_RSVD_38")
		)
		(pad "DK39" smd circle
			(at -4.627626 18.978372)
			(size 0.4318 0.4318)
			(layers "F.Cu" "F.Mask" "F.Paste")
			(net "GND")
		)
		(pad "DK41" smd circle
			(at -2.910586 18.978372)
			(size 0.4318 0.4318)
			(layers "F.Cu" "F.Mask" "F.Paste")
			(net "GND")
		)
		(pad "DK45" smd circle
			(at 2.052066 17.178528)
			(size 0.4318 0.4318)
			(layers "F.Cu" "F.Mask" "F.Paste")
			(net "M_M_CS_N<7>")
		)
		(pad "DK47" smd circle
			(at 3.769106 17.178528)
			(size 0.4318 0.4318)
			(layers "F.Cu" "F.Mask" "F.Paste")
			(net "M_L_CS_N<3>")
		)
		(pad "DK49" smd circle
			(at 5.485892 17.178528)
			(size 0.4318 0.4318)
			(layers "F.Cu" "F.Mask" "F.Paste")
			(net "M_M_ODT<2>")
		)
		(pad "DK51" smd circle
			(at 7.202932 17.178528)
			(size 0.4318 0.4318)
			(layers "F.Cu" "F.Mask" "F.Paste")
			(net "M_M_CS_N<0>")
		)
		(pad "DK53" smd circle
			(at 8.919972 17.178528)
			(size 0.4318 0.4318)
			(layers "F.Cu" "F.Mask" "F.Paste")
			(net "M_M_PAR")
		)
		(pad "DK55" smd circle
			(at 10.637012 17.178528)
			(size 0.4318 0.4318)
			(layers "F.Cu" "F.Mask" "F.Paste")
			(net "M_M_CLK_DN<0>")
		)
		(pad "DK57" smd circle
			(at 12.354052 17.178528)
			(size 0.4318 0.4318)
			(layers "F.Cu" "F.Mask" "F.Paste")
			(net "M_M_CLK_DN<2>")
		)
		(pad "DK59" smd circle
			(at 14.071092 17.178528)
			(size 0.4318 0.4318)
			(layers "F.Cu" "F.Mask" "F.Paste")
			(net "M_M_MA<6>")
		)
		(pad "DK61" smd circle
			(at 15.787878 17.178528)
			(size 0.4318 0.4318)
			(layers "F.Cu" "F.Mask" "F.Paste")
			(net "M_L_MA<7>")
		)
		(pad "DK63" smd circle
			(at 17.504918 17.178528)
			(size 0.4318 0.4318)
			(layers "F.Cu" "F.Mask" "F.Paste")
			(net "M_M_CKE<2>")
		)
		(pad "DK65" smd circle
			(at 19.221958 17.178528)
			(size 0.4318 0.4318)
			(layers "F.Cu" "F.Mask" "F.Paste")
			(net "TP_CPU1_RSVD_37")
		)
		(pad "DK67" smd circle
			(at 20.938998 17.178528)
			(size 0.4318 0.4318)
			(layers "F.Cu" "F.Mask" "F.Paste")
			(net "TP_CPU1_RSVD_36")
		)
		(pad "DK69" smd circle
			(at 22.656038 17.178528)
			(size 0.4318 0.4318)
			(layers "F.Cu" "F.Mask" "F.Paste")
			(net "M_M_DQ<22>")
		)
		(pad "DK71" smd circle
			(at 24.373078 17.178528)
			(size 0.4318 0.4318)
			(layers "F.Cu" "F.Mask" "F.Paste")
			(net "M_M_DQS_DP<2>")
		)
		(pad "DK73" smd circle
			(at 26.090118 17.178528)
			(size 0.4318 0.4318)
			(layers "F.Cu" "F.Mask" "F.Paste")
			(net "GND")
		)
		(pad "DK75" smd circle
			(at 27.806904 17.178528)
			(size 0.4318 0.4318)
			(layers "F.Cu" "F.Mask" "F.Paste")
			(net "GND")
		)
		(pad "DK77" smd circle
			(at 29.523944 17.178528)
			(size 0.4318 0.4318)
			(layers "F.Cu" "F.Mask" "F.Paste")
			(net "GND")
		)
		(pad "DK79" smd circle
			(at 31.240984 17.178528)
			(size 0.4318 0.4318)
			(layers "F.Cu" "F.Mask" "F.Paste")
			(net "M_K_DQ<20>")
		)
		(pad "DK81" smd circle
			(at 32.958024 17.178528)
			(size 0.4318 0.4318)
			(layers "F.Cu" "F.Mask" "F.Paste")
			(net "M_K_DQ<17>")
		)
		(pad "DK83" smd circle
			(at 34.675064 17.178528)
			(size 0.4318 0.4318)
			(layers "F.Cu" "F.Mask" "F.Paste")
			(net "GND")
		)
		(pad "DK85" smd custom
			(at 36.392104 17.178528 270)
			(size 0.10795 0.10795)
			(layers "F.Cu" "F.Mask" "F.Paste")
			(net "GND")
			(options
				(clearance outline)
				(anchor circle)
			)
			(primitives
				(gr_poly
					(pts
						(arc
							(start 0.2159 -0.0381)
							(mid 0 -0.254)
							(end -0.2159 -0.0381)
						)
						(arc
							(start -0.2159 0.0381)
							(mid 0 0.254)
							(end 0.2159 0.0381)
						)
					)
					(width 0)
					(fill yes)
				)
			)
		)
		(pad "DL2" smd custom
			(at -36.392104 19.473926 90)
			(size 0.10795 0.10795)
			(layers "F.Cu" "F.Mask" "F.Paste")
			(net "TP_P3E_CPU1_PE1_MP_TXP<6>")
			(options
				(clearance outline)
				(anchor circle)
			)
			(primitives
				(gr_poly
					(pts
						(arc
							(start 0.2159 -0.0381)
							(mid 0 -0.254)
							(end -0.2159 -0.0381)
						)
						(arc
							(start -0.2159 0.0381)
							(mid 0 0.254)
							(end 0.2159 0.0381)
						)
					)
					(width 0)
					(fill yes)
				)
			)
		)
		(pad "DL4" smd circle
			(at -34.675064 19.473926)
			(size 0.4318 0.4318)
			(layers "F.Cu" "F.Mask" "F.Paste")
			(net "GND")
		)
		(pad "DL6" smd circle
			(at -32.958024 19.473926)
			(size 0.4318 0.4318)
			(layers "F.Cu" "F.Mask" "F.Paste")
			(net "P3E_CPU1_PE3_MP_TXN<10>")
		)
		(pad "DL8" smd circle
			(at -31.240984 19.473926)
			(size 0.4318 0.4318)
			(layers "F.Cu" "F.Mask" "F.Paste")
			(net "GND")
		)
		(pad "DL10" smd circle
			(at -29.523944 19.473926)
			(size 0.4318 0.4318)
			(layers "F.Cu" "F.Mask" "F.Paste")
			(net "TP_P3E_CPU1_PE1_MP_RXP<7>")
		)
		(pad "DL12" smd circle
			(at -27.806904 19.473926)
			(size 0.4318 0.4318)
			(layers "F.Cu" "F.Mask" "F.Paste")
			(net "P3E_CPU1_PE3_MP_RXN<8>")
		)
		(pad "DL14" smd circle
			(at -26.090118 19.473926)
			(size 0.4318 0.4318)
			(layers "F.Cu" "F.Mask" "F.Paste")
			(net "P3E_CPU1_PE3_MP_RXN<7>")
		)
		(pad "DL16" smd circle
			(at -24.373078 19.473926)
			(size 0.4318 0.4318)
			(layers "F.Cu" "F.Mask" "F.Paste")
			(net "GND")
		)
		(pad "DL18" smd circle
			(at -22.656038 19.473926)
			(size 0.4318 0.4318)
			(layers "F.Cu" "F.Mask" "F.Paste")
			(net "GND")
		)
		(pad "DL20" smd circle
			(at -20.938998 19.473926)
			(size 0.4318 0.4318)
			(layers "F.Cu" "F.Mask" "F.Paste")
			(net "TP_CPU1_UPI2_RSVD_CE12")
		)
		(pad "DL22" smd circle
			(at -19.221958 19.473926)
			(size 0.4318 0.4318)
			(layers "F.Cu" "F.Mask" "F.Paste")
			(net "GND")
		)
		(pad "DL24" smd circle
			(at -17.504918 19.473926)
			(size 0.4318 0.4318)
			(layers "F.Cu" "F.Mask" "F.Paste")
			(net "GND")
		)
		(pad "DL26" smd circle
			(at -15.787878 19.473926)
			(size 0.4318 0.4318)
			(layers "F.Cu" "F.Mask" "F.Paste")
			(net "M_L_DQS_DN<7>")
		)
		(pad "DL28" smd circle
			(at -14.071092 19.473926)
			(size 0.4318 0.4318)
			(layers "F.Cu" "F.Mask" "F.Paste")
			(net "GND")
		)
		(pad "DL30" smd circle
			(at -12.354052 19.473926)
			(size 0.4318 0.4318)
			(layers "F.Cu" "F.Mask" "F.Paste")
			(net "GND")
		)
		(pad "DL32" smd circle
			(at -10.637012 19.473926)
			(size 0.4318 0.4318)
			(layers "F.Cu" "F.Mask" "F.Paste")
			(net "M_M_DQS_DN<5>")
		)
		(pad "DL34" smd circle
			(at -8.919972 19.473926)
			(size 0.4318 0.4318)
			(layers "F.Cu" "F.Mask" "F.Paste")
			(net "GND")
		)
		(pad "DL36" smd circle
			(at -7.202932 19.473926)
			(size 0.4318 0.4318)
			(layers "F.Cu" "F.Mask" "F.Paste")
			(net "GND")
		)
		(pad "DL38" smd circle
			(at -5.485892 19.473926)
			(size 0.4318 0.4318)
			(layers "F.Cu" "F.Mask" "F.Paste")
			(net "TP_CPU1_RSVD_35")
		)
		(pad "DL40" smd circle
			(at -3.769106 19.473926)
			(size 0.4318 0.4318)
			(layers "F.Cu" "F.Mask" "F.Paste")
			(net "GND")
		)
		(pad "DL42" smd circle
			(at -2.052066 19.473926)
			(size 0.4318 0.4318)
			(layers "F.Cu" "F.Mask" "F.Paste")
			(net "M_L_DQ<36>")
		)
		(pad "DL44" smd circle
			(at 1.193546 17.673574)
			(size 0.508 0.508)
			(layers "F.Cu" "F.Mask" "F.Paste")
			(net "SVID_ALERT1_CPU1_N")
		)
		(pad "DL46" smd circle
			(at 2.910586 17.673574)
			(size 0.4318 0.4318)
			(layers "F.Cu" "F.Mask" "F.Paste")
			(net "PVDDQ_KLM")
		)
		(pad "DL48" smd circle
			(at 4.627626 17.673574)
			(size 0.4318 0.4318)
			(layers "F.Cu" "F.Mask" "F.Paste")
			(net "PVDDQ_KLM")
		)
		(pad "DL50" smd circle
			(at 6.344412 17.673574)
			(size 0.4318 0.4318)
			(layers "F.Cu" "F.Mask" "F.Paste")
			(net "PVDDQ_KLM")
		)
		(pad "DL52" smd circle
			(at 8.061452 17.673574)
			(size 0.4318 0.4318)
			(layers "F.Cu" "F.Mask" "F.Paste")
			(net "PVDDQ_KLM")
		)
		(pad "DL54" smd circle
			(at 9.778492 17.673574)
			(size 0.4318 0.4318)
			(layers "F.Cu" "F.Mask" "F.Paste")
			(net "PVDDQ_KLM")
		)
		(pad "DL56" smd circle
			(at 11.495532 17.673574)
			(size 0.4318 0.4318)
			(layers "F.Cu" "F.Mask" "F.Paste")
			(net "PVDDQ_KLM")
		)
		(pad "DL58" smd circle
			(at 13.212572 17.673574)
			(size 0.4318 0.4318)
			(layers "F.Cu" "F.Mask" "F.Paste")
			(net "PVDDQ_KLM")
		)
		(pad "DL60" smd circle
			(at 14.929612 17.673574)
			(size 0.4318 0.4318)
			(layers "F.Cu" "F.Mask" "F.Paste")
			(net "PVDDQ_KLM")
		)
		(pad "DL62" smd circle
			(at 16.646398 17.673574)
			(size 0.4318 0.4318)
			(layers "F.Cu" "F.Mask" "F.Paste")
			(net "PVDDQ_KLM")
		)
		(pad "DL64" smd circle
			(at 18.363438 17.673574)
			(size 0.4318 0.4318)
			(layers "F.Cu" "F.Mask" "F.Paste")
			(net "M_L_CKE<2>")
		)
		(pad "DL66" smd circle
			(at 20.080478 17.673574)
			(size 0.4318 0.4318)
			(layers "F.Cu" "F.Mask" "F.Paste")
			(net "TP_CPU1_RSVD_34")
		)
		(pad "DL68" smd circle
			(at 21.797518 17.673574)
			(size 0.4318 0.4318)
			(layers "F.Cu" "F.Mask" "F.Paste")
			(net "GND")
		)
		(pad "DL70" smd circle
			(at 23.514558 17.673574)
			(size 0.4318 0.4318)
			(layers "F.Cu" "F.Mask" "F.Paste")
			(net "GND")
		)
		(pad "DL72" smd circle
			(at 25.231598 17.673574)
			(size 0.4318 0.4318)
			(layers "F.Cu" "F.Mask" "F.Paste")
			(net "M_M_DQS_DN<2>")
		)
		(pad "DL74" smd circle
			(at 26.948384 17.673574)
			(size 0.4318 0.4318)
			(layers "F.Cu" "F.Mask" "F.Paste")
			(net "GND")
		)
		(pad "DL76" smd circle
			(at 28.665424 17.673574)
			(size 0.4318 0.4318)
			(layers "F.Cu" "F.Mask" "F.Paste")
			(net "GND")
		)
		(pad "DL78" smd circle
			(at 30.382464 17.673574)
			(size 0.4318 0.4318)
			(layers "F.Cu" "F.Mask" "F.Paste")
			(net "GND")
		)
		(pad "DL80" smd circle
			(at 32.099504 17.673574)
			(size 0.4318 0.4318)
			(layers "F.Cu" "F.Mask" "F.Paste")
			(net "GND")
		)
		(pad "DL82" smd circle
			(at 33.816544 17.673574)
			(size 0.4318 0.4318)
			(layers "F.Cu" "F.Mask" "F.Paste")
			(net "M_K_DQS_DN<2>")
		)
		(pad "DL84" smd circle
			(at 35.533584 17.673574)
			(size 0.4318 0.4318)
			(layers "F.Cu" "F.Mask" "F.Paste")
			(net "M_K_DQS_DP<10>")
		)
		(pad "DM3" smd circle
			(at -35.533584 19.968972)
			(size 0.4318 0.4318)
			(layers "F.Cu" "F.Mask" "F.Paste")
			(net "TP_P3E_CPU1_PE1_MP_TXN<6>")
		)
		(pad "DM5" smd circle
			(at -33.816544 19.968972)
			(size 0.4318 0.4318)
			(layers "F.Cu" "F.Mask" "F.Paste")
			(net "P3E_CPU1_PE3_MP_TXP<9>")
		)
		(pad "DM7" smd circle
			(at -32.099504 19.968972)
			(size 0.4318 0.4318)
			(layers "F.Cu" "F.Mask" "F.Paste")
			(net "P3E_CPU1_PE3_MP_TXN<8>")
		)
		(pad "DM9" smd circle
			(at -30.382464 19.968972)
			(size 0.4318 0.4318)
			(layers "F.Cu" "F.Mask" "F.Paste")
			(net "TP_P3E_CPU1_PE1_MP_RXN<7>")
		)
		(pad "DM11" smd circle
			(at -28.665424 19.968972)
			(size 0.4318 0.4318)
			(layers "F.Cu" "F.Mask" "F.Paste")
			(net "TP_P3E_CPU1_PE1_RSR3_RXN<8>")
		)
	)
)
